# S9S_MB_2U (Grand Teton) — schematic netlist excerpt (pin names and nets, part order shuffled) for the footprints in the layout excerpt that follows; sources: Cadence DE-HDL packaged netlist, KiCad conversion of 03242023_DA0F0TMBIJ0_F0T_Motherboard_J_brd_V01_OCP.brd

J9  SCONN288_ADR50017P130CC  SCONN288_ADR50017-P130CC IO  pkg DDR288S_1-1VXB  page 90
  VIN_BULK0  = P12V_S3_AUX_CPU0_NVDIMM
  RFU0  = TP_CHE_CPU0_DIMM1_FRU_0
  VIN_MGMT  = P3V3_AUX
  HSCL  = I3C_SPD_DDREFGH_CPU0_LVC1_SCL_R
  HSDA  = I3C_SPD_DDREFGH_CPU0_LVC1_SDA
  VSS0  = GND
  DQ0_A  = M_E_CPU0_SA_DQ<0>
  VSS1  = GND
  DQ1_A  = M_E_CPU0_SA_DQ<1>
  VSS2  = GND
  DQS0_A_T  = M_E_CPU0_SA_DQS_DP<0>
  DQS0_A_C  = M_E_CPU0_SA_DQS_DN<0>
  VSS3  = GND
  DQ4_A  = M_E_CPU0_SA_DQ<4>
  VSS4  = GND
  DQ5_A  = M_E_CPU0_SA_DQ<5>
  VSS5  = GND
  DQ8_A  = M_E_CPU0_SA_DQ<8>
  VSS6  = GND
  DQ9_A  = M_E_CPU0_SA_DQ<9>
  VSS7  = GND
  DQS1_A_T  = M_E_CPU0_SA_DQS_DP<1>
  DQS1_A_C  = M_E_CPU0_SA_DQS_DN<1>
  VSS8  = GND
  DQ12_A  = M_E_CPU0_SA_DQ<12>
  VSS9  = GND
  DQ13_A  = M_E_CPU0_SA_DQ<13>
  VSS10  = GND
  DQ16_A  = M_E_CPU0_SA_DQ<16>
  VSS11  = GND
  DQ17_A  = M_E_CPU0_SA_DQ<17>
  VSS12  = GND
  DQS2_A_T  = M_E_CPU0_SA_DQS_DP<2>
  DQS2_A_C  = M_E_CPU0_SA_DQS_DN<2>
  VSS13  = GND
  DQ20_A  = M_E_CPU0_SA_DQ<20>
  VSS14  = GND
  DQ21_A  = M_E_CPU0_SA_DQ<21>
  VSS15  = GND
  DQ24_A  = M_E_CPU0_SA_DQ<24>
  VSS16  = GND
  DQ25_A  = M_E_CPU0_SA_DQ<25>
  VSS17  = GND
  DQS3_A_T  = M_E_CPU0_SA_DQS_DP<3>
  DQS3_A_C  = M_E_CPU0_SA_DQS_DN<3>
  VSS18  = GND
  DQ28_A  = M_E_CPU0_SA_DQ<28>
  VSS19  = GND
  DQ29_A  = M_E_CPU0_SA_DQ<29>
  VSS20  = GND
  CB0_A  = M_E_CPU0_SA_CB<0>
  VSS21  = GND
  CB1_A  = M_E_CPU0_SA_CB<1>
  VSS22  = GND
  DQS4_A_T  = M_E_CPU0_SA_DQS_DP<4>
  DQS4_A_C  = M_E_CPU0_SA_DQS_DN<4>
  VSS23  = GND
  CB4_A  = M_E_CPU0_SA_CB<4>
  VSS24  = GND
  CB5_A  = M_E_CPU0_SA_CB<5>
  VSS25  = GND
  ALERT_N  = M_E_CPU0_ALERT_N
  VSS26  = GND
  CS0_A_N  = M_E_CPU0_SA_CS_N<0>
  VSS27  = GND
  CA0_A  = M_E_CPU0_SA_CA<0>
  VSS28  = GND
  CA2_A  = M_E_CPU0_SA_CA<2>
  VSS29  = GND
  CA4_A  = M_E_CPU0_SA_CA<4>
  VSS30  = GND
  CA6_A  = M_E_CPU0_SA_CA<6>
  VSS31  = GND
  PAR_A  = M_E_CPU0_SA_PAR
  VSS32  = GND
  CA0_B  = M_E_CPU0_SB_CA<0>
  VSS33  = GND
  CA2_B  = M_E_CPU0_SB_CA<2>
  VSS34  = GND
  CA4_B  = M_E_CPU0_SB_CA<4>
  VSS35  = GND
  CA6_B  = M_E_CPU0_SB_CA<6>
  VSS36  = GND
  CS0_B_N  = M_E_CPU0_SB_CS_N<0>
  VSS37  = GND
  \lbd||rsp_a_n\  = M_E_CPU0_SA_RSP<0>
  \lbs||rsp_b_n\  = M_E_CPU0_SB_RSP<0>
  VSS38  = GND
  CB4_B  = M_E_CPU0_SB_CB<4>
  VSS39  = GND
  CB5_B  = M_E_CPU0_SB_CB<5>
  VSS40  = GND
  \dqs9_b_t||tdqs9_b_t||dbi4_b_n\  = M_E_CPU0_SB_DQS_DP<9>
  \dqs9_b_c||tdqs9_b_c\  = M_E_CPU0_SB_DQS_DN<9>
  VSS41  = GND
  CB0_B  = M_E_CPU0_SB_CB<0>
  VSS42  = GND
  CB1_B  = M_E_CPU0_SB_CB<1>
  VSS43  = GND
  DQ0_B  = M_E_CPU0_SB_DQ<0>
  VSS44  = GND
  DQ1_B  = M_E_CPU0_SB_DQ<1>
  VSS45  = GND
  DQS0_B_T  = M_E_CPU0_SB_DQS_DP<0>
  DQS0_B_C  = M_E_CPU0_SB_DQS_DN<0>
  VSS46  = GND
  DQ4_B  = M_E_CPU0_SB_DQ<4>
  VSS47  = GND
  DQ5_B  = M_E_CPU0_SB_DQ<5>
  VSS48  = GND
  DQ8_B  = M_E_CPU0_SB_DQ<8>
  VSS49  = GND
  DQ9_B  = M_E_CPU0_SB_DQ<9>
  VSS50  = GND
  DQS1_B_T  = M_E_CPU0_SB_DQS_DP<1>
  DQS1_B_C  = M_E_CPU0_SB_DQS_DN<1>
  VSS51  = GND
  DQ12_B  = M_E_CPU0_SB_DQ<12>
  VSS52  = GND
  DQ13_B  = M_E_CPU0_SB_DQ<13>
  VSS53  = GND
  DQ16_B  = M_E_CPU0_SB_DQ<16>
  VSS54  = GND
  DQ17_B  = M_E_CPU0_SB_DQ<17>
  VSS55  = GND
  DQS2_B_T  = M_E_CPU0_SB_DQS_DP<2>
  DQS2_B_C  = M_E_CPU0_SB_DQS_DN<2>
  VSS56  = GND
  DQ20_B  = M_E_CPU0_SB_DQ<20>
  VSS57  = GND
  DQ21_B  = M_E_CPU0_SB_DQ<21>
  VSS58  = GND
  DQ24_B  = M_E_CPU0_SB_DQ<24>
  VSS59  = GND
  DQ25_B  = M_E_CPU0_SB_DQ<25>
  VSS60  = GND
  DQS3_B_T  = M_E_CPU0_SB_DQS_DP<3>
  DQS3_B_C  = M_E_CPU0_SB_DQS_DN<3>
  VSS61  = GND
  DQ28_B  = M_E_CPU0_SB_DQ<28>
  VSS62  = GND
  DQ29_B  = M_E_CPU0_SB_DQ<29>
  VSS63  = GND
  RFU1  = TP_CHE_CPU0_DIMM1_FRU_1
  VIN_BULK1  = P12V_S3_AUX_CPU0_NVDIMM
  VIN_BULK2  = P12V_S3_AUX_CPU0_NVDIMM
  \pwr_good||fail_n\  = PWRGD_CHE_CPU0_DIMM1
  HSA  = PD_CHE_CPU0_DIMM1_SAA
  RFU2  = TP_CHE_CPU0_DIMM1_FRU_2
  RFU3  = TP_CHE_CPU0_DIMM1_FRU_3
  VSS64  = GND
  DQ2_A  = M_E_CPU0_SA_DQ<2>
  VSS65  = GND
  DQ3_A  = M_E_CPU0_SA_DQ<3>
  VSS66  = GND
  \dqs5_a_c||tdqs5_a_c||dqs5_a_t||tdqs5_a_t\  = M_E_CPU0_SA_DQS_DN<5>
  \dqs5_a_t||tdqs5_a_t\  = M_E_CPU0_SA_DQS_DP<5>
  VSS67  = GND
  DQ6_A  = M_E_CPU0_SA_DQ<6>
  VSS68  = GND
  DQ7_A  = M_E_CPU0_SA_DQ<7>
  VSS69  = GND
  DQ10_A  = M_E_CPU0_SA_DQ<10>
  VSS70  = GND
  DQ11_A  = M_E_CPU0_SA_DQ<11>
  VSS71  = GND
  \dqs6_a_c||tdqs6_a_c||dqs6_a_t||tdqs6_a_t\  = M_E_CPU0_SA_DQS_DN<6>
  \dqs6_a_t||tdqs6_a_t\  = M_E_CPU0_SA_DQS_DP<6>
  VSS72  = GND
  DQ14_A  = M_E_CPU0_SA_DQ<14>
  VSS73  = GND
  DQ15_A  = M_E_CPU0_SA_DQ<15>
  VSS74  = GND
  DQ18_A  = M_E_CPU0_SA_DQ<18>
  VSS75  = GND
  DQ19_A  = M_E_CPU0_SA_DQ<19>
  VSS76  = GND
  \dqs7_a_c||tdqs7_a_c\  = M_E_CPU0_SA_DQS_DN<7>
  \dqs7_a_t||tdqs7_a_t\  = M_E_CPU0_SA_DQS_DP<7>
  VSS77  = GND
  DQ22_A  = M_E_CPU0_SA_DQ<22>
  VSS78  = GND
  DQ23_A  = M_E_CPU0_SA_DQ<23>
  VSS79  = GND
  DQ26_A  = M_E_CPU0_SA_DQ<26>
  VSS80  = GND
  DQ27_A  = M_E_CPU0_SA_DQ<27>
  VSS81  = GND
  \dqs8_a_c||tdqs8_a_c\  = M_E_CPU0_SA_DQS_DN<8>
  \dqs8_a_t||tdqs8_a_t\  = M_E_CPU0_SA_DQS_DP<8>
  VSS82  = GND
  DQ30_A  = M_E_CPU0_SA_DQ<30>
  VSS83  = GND
  DQ31_A  = M_E_CPU0_SA_DQ<31>
  VSS84  = GND
  CB2_A  = M_E_CPU0_SA_CB<2>
  VSS85  = GND
  CB3_A  = M_E_CPU0_SA_CB<3>
  VSS86  = GND
  \dqs9_a_c||tdqs9_a_c\  = M_E_CPU0_SA_DQS_DN<9>
  \dqs9_a_t||tdqs9_a_t\  = M_E_CPU0_SA_DQS_DP<9>
  VSS87  = GND
  CB6_A  = M_E_CPU0_SA_CB<6>
  VSS88  = GND
  CB7_A  = M_E_CPU0_SA_CB<7>
  VSS89  = GND
  RESET_N  = RST_M_EF_CPU0_FPGA_N
  VSS90  = GND
  CS1_A_N  = M_E_CPU0_SA_CS_N<1>
  VSS91  = GND
  CA1_A  = M_E_CPU0_SA_CA<1>
  VSS92  = GND
  CA3_A  = M_E_CPU0_SA_CA<3>
  VSS93  = GND
  CA5_A  = M_E_CPU0_SA_CA<5>
  VSS94  = GND
  CK_T  = M_E_CPU0_CLK_DP<0>
  CK_C  = M_E_CPU0_CLK_DN<0>
  VSS95  = GND
  RFU4  = TP_CHE_CPU0_DIMM1_FRU_4
  CA1_B  = M_E_CPU0_SB_CA<1>
  VSS96  = GND
  CA3_B  = M_E_CPU0_SB_CA<3>
  VSS97  = GND
  CA5_B  = M_E_CPU0_SB_CA<5>
  VSS98  = GND
  PAR_B  = M_E_CPU0_SB_PAR
  VSS99  = GND
  CS1_B_N  = M_E_CPU0_SB_CS_N<1>
  VSS100  = GND
  RFU5  = TP_CHE_CPU0_DIMM1_FRU_5
  RFU6  = TP_CHE_CPU0_DIMM1_FRU_6
  VSS101  = GND
  CB6_B  = M_E_CPU0_SB_CB<6>
  VSS102  = GND
  CB7_B  = M_E_CPU0_SB_CB<7>
  VSS103  = GND
  DQS4_B_C  = M_E_CPU0_SB_DQS_DN<4>
  DQS4_B_T  = M_E_CPU0_SB_DQS_DP<4>
  VSS104  = GND
  CB2_B  = M_E_CPU0_SB_CB<2>
  VSS105  = GND
  CB3_B  = M_E_CPU0_SB_CB<3>
  VSS106  = GND
  DQ2_B  = M_E_CPU0_SB_DQ<2>
  VSS107  = GND
  DQ3_B  = M_E_CPU0_SB_DQ<3>
  VSS108  = GND
  \dqs5_b_c||tdqs5_b_c\  = M_E_CPU0_SB_DQS_DN<5>
  \dqs5_b_t||tdqs5_b_t\  = M_E_CPU0_SB_DQS_DP<5>
  VSS109  = GND
  DQ6_B  = M_E_CPU0_SB_DQ<6>
  VSS110  = GND
  DQ7_B  = M_E_CPU0_SB_DQ<7>
  VSS111  = GND
  DQ10_B  = M_E_CPU0_SB_DQ<10>
  VSS112  = GND
  DQ11_B  = M_E_CPU0_SB_DQ<11>
  VSS113  = GND
  \dqs6_b_c||tdqs6_b_c\  = M_E_CPU0_SB_DQS_DN<6>
  \dqs6_b_t||tdqs6_b_t\  = M_E_CPU0_SB_DQS_DP<6>
  VSS114  = GND
  DQ14_B  = M_E_CPU0_SB_DQ<14>
  VSS115  = GND
  DQ15_B  = M_E_CPU0_SB_DQ<15>
  VSS116  = GND
  DQ18_B  = M_E_CPU0_SB_DQ<18>
  VSS117  = GND
  DQ19_B  = M_E_CPU0_SB_DQ<19>
  VSS118  = GND
  \dqs7_b_c||tdqs7_b_c\  = M_E_CPU0_SB_DQS_DN<7>
  \dqs7_b_t||tdqs7_b_t\  = M_E_CPU0_SB_DQS_DP<7>
  VSS119  = GND
  DQ22_B  = M_E_CPU0_SB_DQ<22>
  VSS120  = GND
  DQ23_B  = M_E_CPU0_SB_DQ<23>
  VSS121  = GND
  DQ26_B  = M_E_CPU0_SB_DQ<26>
  VSS122  = GND
  DQ27_B  = M_E_CPU0_SB_DQ<27>
  VSS123  = GND
  \dqs8_b_c||tdqs8_b_c\  = M_E_CPU0_SB_DQS_DN<8>
  \dqs8_b_t||tdqs8_b_t\  = M_E_CPU0_SB_DQS_DP<8>
  VSS124  = GND
  DQ30_B  = M_E_CPU0_SB_DQ<30>
  VSS125  = GND
  DQ31_B  = M_E_CPU0_SB_DQ<31>
  VSS126  = GND
  G1  = GND
  G2  = GND
  G3  = GND

(kicad_pcb
	(version 20260206)
	(generator "pcbnew")
	(generator_version "10.0")
	(general
		(thickness 1.6)
		(legacy_teardrops no)
	)
	(paper "A4")
	(title_block
		(title "03242023_DA0F0TMBIJ0_F0T_Motherboard_J_brd_V01_OCP.brd")
		(comment 1 "Grand Teton / footprint 461 of 6105 (J9), pads 138-182 of 291")
	)
	(layers
		(0 "F.Cu" signal "TOP")
		(4 "In1.Cu" signal "GND")
		(6 "In2.Cu" signal "IN1")
		(8 "In3.Cu" signal "GND1")
		(10 "In4.Cu" signal "IN2")
		(12 "In5.Cu" signal "GND2")
		(14 "In6.Cu" signal "IN3")
		(16 "In7.Cu" signal "GND3")
		(18 "In8.Cu" signal "VCC")
		(20 "In9.Cu" signal "VCC1")
		(22 "In10.Cu" signal "GND4")
		(24 "In11.Cu" signal "IN4")
		(26 "In12.Cu" signal "GND5")
		(28 "In13.Cu" signal "IN5")
		(30 "In14.Cu" signal "GND6")
		(32 "In15.Cu" signal "IN6")
		(34 "In16.Cu" signal "GND7")
		(2 "B.Cu" signal "BOTTOM")
		(9 "F.Adhes" user "F.Adhesive")
		(11 "B.Adhes" user "B.Adhesive")
		(13 "F.Paste" user "Package Geometry/Pastemask Top")
		(15 "B.Paste" user "Package Geometry/Pastemask Bottom")
		(5 "F.SilkS" user "Ref Des/Silkscreen Top")
		(7 "B.SilkS" user "Ref Des/Silkscreen Bottom")
		(1 "F.Mask" user "Board Geometry/Soldermask Top")
		(3 "B.Mask" user "Board Geometry/Soldermask Bottom")
		(17 "Dwgs.User" user "User.Drawings")
		(19 "Cmts.User" user "User.Comments")
		(21 "Eco1.User" user "User.Eco1")
		(23 "Eco2.User" user "User.Eco2")
		(25 "Edge.Cuts" user "Board Geometry/Outline")
		(27 "Margin" user)
		(31 "F.CrtYd" user "Package Geometry/Place Bound Top")
		(29 "B.CrtYd" user "Package Geometry/Place Bound Bottom")
		(35 "F.Fab" user "Ref Des/Assembly Top")
		(33 "B.Fab" user "Ref Des/Assembly Bottom")
	)
	(footprint ""
		(layer "F.Cu")
		(at 416.347148 -258.091686)
		(property "Reference" "J9"
			(at -3.683 -81.702148 0)
			(unlocked yes)
			(layer "F.SilkS")
			(effects
				(font
					(size 0.7874 0.5842)
					(thickness 0.1524)
				)
				(justify left)
			)
		)
		(property "Value" ""
			(at 0 0 0)
			(layer "F.Fab")
			(effects
				(font
					(size 1.27 1.27)
				)
			)
		)
		(duplicate_pad_numbers_are_jumpers no)
		(pad "138" smd rect
			(at -2.050034 58.224928 270)
			(size 0.519938 1.4986)
			(layers "F.Cu" "F.Mask" "F.Paste")
			(net "M_E_CPU0_SB_DQS_DN<3>")
		)
		(pad "139" smd rect
			(at -2.050034 59.075066 270)
			(size 0.519938 1.4986)
			(layers "F.Cu" "F.Mask" "F.Paste")
			(net "GND")
		)
		(pad "140" smd rect
			(at -2.050034 59.92495 270)
			(size 0.519938 1.4986)
			(layers "F.Cu" "F.Mask" "F.Paste")
			(net "M_E_CPU0_SB_DQ<28>")
		)
		(pad "141" smd rect
			(at -2.050034 60.775088 270)
			(size 0.519938 1.4986)
			(layers "F.Cu" "F.Mask" "F.Paste")
			(net "GND")
		)
		(pad "142" smd rect
			(at -2.050034 61.624972 270)
			(size 0.519938 1.4986)
			(layers "F.Cu" "F.Mask" "F.Paste")
			(net "M_E_CPU0_SB_DQ<29>")
		)
		(pad "143" smd rect
			(at -2.050034 62.47511 270)
			(size 0.519938 1.4986)
			(layers "F.Cu" "F.Mask" "F.Paste")
			(net "GND")
		)
		(pad "144" smd rect
			(at -2.050034 63.324994 270)
			(size 0.519938 1.4986)
			(layers "F.Cu" "F.Mask" "F.Paste")
			(net "TP_CHE_CPU0_DIMM1_FRU_1")
		)
		(pad "145" smd rect
			(at 2.050034 -63.324994 270)
			(size 0.519938 1.4986)
			(layers "F.Cu" "F.Mask" "F.Paste")
			(net "P12V_S3_AUX_CPU0_NVDIMM")
		)
		(pad "146" smd rect
			(at 2.050034 -62.47511 270)
			(size 0.519938 1.4986)
			(layers "F.Cu" "F.Mask" "F.Paste")
			(net "P12V_S3_AUX_CPU0_NVDIMM")
		)
		(pad "147" smd rect
			(at 2.050034 -61.624972 270)
			(size 0.519938 1.4986)
			(layers "F.Cu" "F.Mask" "F.Paste")
			(net "PWRGD_CHE_CPU0_DIMM1")
		)
		(pad "148" smd rect
			(at 2.050034 -60.775088 270)
			(size 0.519938 1.4986)
			(layers "F.Cu" "F.Mask" "F.Paste")
			(net "PD_CHE_CPU0_DIMM1_SAA")
		)
		(pad "149" smd rect
			(at 2.050034 -59.92495 270)
			(size 0.519938 1.4986)
			(layers "F.Cu" "F.Mask" "F.Paste")
			(net "TP_CHE_CPU0_DIMM1_FRU_2")
		)
		(pad "150" smd rect
			(at 2.050034 -59.075066 270)
			(size 0.519938 1.4986)
			(layers "F.Cu" "F.Mask" "F.Paste")
			(net "TP_CHE_CPU0_DIMM1_FRU_3")
		)
		(pad "151" smd rect
			(at 2.050034 -58.224928 270)
			(size 0.519938 1.4986)
			(layers "F.Cu" "F.Mask" "F.Paste")
			(net "GND")
		)
		(pad "152" smd rect
			(at 2.050034 -57.375044 270)
			(size 0.519938 1.4986)
			(layers "F.Cu" "F.Mask" "F.Paste")
			(net "M_E_CPU0_SA_DQ<2>")
		)
		(pad "153" smd rect
			(at 2.050034 -56.524906 270)
			(size 0.519938 1.4986)
			(layers "F.Cu" "F.Mask" "F.Paste")
			(net "GND")
		)
		(pad "154" smd rect
			(at 2.050034 -55.675022 270)
			(size 0.519938 1.4986)
			(layers "F.Cu" "F.Mask" "F.Paste")
			(net "M_E_CPU0_SA_DQ<3>")
		)
		(pad "155" smd rect
			(at 2.050034 -54.824884 270)
			(size 0.519938 1.4986)
			(layers "F.Cu" "F.Mask" "F.Paste")
			(net "GND")
		)
		(pad "156" smd rect
			(at 2.050034 -53.975 270)
			(size 0.519938 1.4986)
			(layers "F.Cu" "F.Mask" "F.Paste")
			(net "M_E_CPU0_SA_DQS_DN<5>")
		)
		(pad "157" smd rect
			(at 2.050034 -53.125116 270)
			(size 0.519938 1.4986)
			(layers "F.Cu" "F.Mask" "F.Paste")
			(net "M_E_CPU0_SA_DQS_DP<5>")
		)
		(pad "158" smd rect
			(at 2.050034 -52.274978 270)
			(size 0.519938 1.4986)
			(layers "F.Cu" "F.Mask" "F.Paste")
			(net "GND")
		)
		(pad "159" smd rect
			(at 2.050034 -51.425094 270)
			(size 0.519938 1.4986)
			(layers "F.Cu" "F.Mask" "F.Paste")
			(net "M_E_CPU0_SA_DQ<6>")
		)
		(pad "160" smd rect
			(at 2.050034 -50.574956 270)
			(size 0.519938 1.4986)
			(layers "F.Cu" "F.Mask" "F.Paste")
			(net "GND")
		)
		(pad "161" smd rect
			(at 2.050034 -49.725072 270)
			(size 0.519938 1.4986)
			(layers "F.Cu" "F.Mask" "F.Paste")
			(net "M_E_CPU0_SA_DQ<7>")
		)
		(pad "162" smd rect
			(at 2.050034 -48.874934 270)
			(size 0.519938 1.4986)
			(layers "F.Cu" "F.Mask" "F.Paste")
			(net "GND")
		)
		(pad "163" smd rect
			(at 2.050034 -48.02505 270)
			(size 0.519938 1.4986)
			(layers "F.Cu" "F.Mask" "F.Paste")
			(net "M_E_CPU0_SA_DQ<10>")
		)
		(pad "164" smd rect
			(at 2.050034 -47.174912 270)
			(size 0.519938 1.4986)
			(layers "F.Cu" "F.Mask" "F.Paste")
			(net "GND")
		)
		(pad "165" smd rect
			(at 2.050034 -46.325028 270)
			(size 0.519938 1.4986)
			(layers "F.Cu" "F.Mask" "F.Paste")
			(net "M_E_CPU0_SA_DQ<11>")
		)
		(pad "166" smd rect
			(at 2.050034 -45.47489 270)
			(size 0.519938 1.4986)
			(layers "F.Cu" "F.Mask" "F.Paste")
			(net "GND")
		)
		(pad "167" smd rect
			(at 2.050034 -44.625006 270)
			(size 0.519938 1.4986)
			(layers "F.Cu" "F.Mask" "F.Paste")
			(net "M_E_CPU0_SA_DQS_DN<6>")
		)
		(pad "168" smd rect
			(at 2.050034 -43.775122 270)
			(size 0.519938 1.4986)
			(layers "F.Cu" "F.Mask" "F.Paste")
			(net "M_E_CPU0_SA_DQS_DP<6>")
		)
		(pad "169" smd rect
			(at 2.050034 -42.924984 270)
			(size 0.519938 1.4986)
			(layers "F.Cu" "F.Mask" "F.Paste")
			(net "GND")
		)
		(pad "170" smd rect
			(at 2.050034 -42.0751 270)
			(size 0.519938 1.4986)
			(layers "F.Cu" "F.Mask" "F.Paste")
			(net "M_E_CPU0_SA_DQ<14>")
		)
		(pad "171" smd rect
			(at 2.050034 -41.224962 270)
			(size 0.519938 1.4986)
			(layers "F.Cu" "F.Mask" "F.Paste")
			(net "GND")
		)
		(pad "172" smd rect
			(at 2.050034 -40.375078 270)
			(size 0.519938 1.4986)
			(layers "F.Cu" "F.Mask" "F.Paste")
			(net "M_E_CPU0_SA_DQ<15>")
		)
		(pad "173" smd rect
			(at 2.050034 -39.52494 270)
			(size 0.519938 1.4986)
			(layers "F.Cu" "F.Mask" "F.Paste")
			(net "GND")
		)
		(pad "174" smd rect
			(at 2.050034 -38.675056 270)
			(size 0.519938 1.4986)
			(layers "F.Cu" "F.Mask" "F.Paste")
			(net "M_E_CPU0_SA_DQ<18>")
		)
		(pad "175" smd rect
			(at 2.050034 -37.824918 270)
			(size 0.519938 1.4986)
			(layers "F.Cu" "F.Mask" "F.Paste")
			(net "GND")
		)
		(pad "176" smd rect
			(at 2.050034 -36.975034 270)
			(size 0.519938 1.4986)
			(layers "F.Cu" "F.Mask" "F.Paste")
			(net "M_E_CPU0_SA_DQ<19>")
		)
		(pad "177" smd rect
			(at 2.050034 -36.124896 270)
			(size 0.519938 1.4986)
			(layers "F.Cu" "F.Mask" "F.Paste")
			(net "GND")
		)
		(pad "178" smd rect
			(at 2.050034 -35.275012 270)
			(size 0.519938 1.4986)
			(layers "F.Cu" "F.Mask" "F.Paste")
			(net "M_E_CPU0_SA_DQS_DN<7>")
		)
		(pad "179" smd rect
			(at 2.050034 -34.425128 270)
			(size 0.519938 1.4986)
			(layers "F.Cu" "F.Mask" "F.Paste")
			(net "M_E_CPU0_SA_DQS_DP<7>")
		)
		(pad "180" smd rect
			(at 2.050034 -33.57499 270)
			(size 0.519938 1.4986)
			(layers "F.Cu" "F.Mask" "F.Paste")
			(net "GND")
		)
		(pad "181" smd rect
			(at 2.050034 -32.725106 270)
			(size 0.519938 1.4986)
			(layers "F.Cu" "F.Mask" "F.Paste")
			(net "M_E_CPU0_SA_DQ<22>")
		)
		(pad "182" smd rect
			(at 2.050034 -31.874968 270)
			(size 0.519938 1.4986)
			(layers "F.Cu" "F.Mask" "F.Paste")
			(net "GND")
		)
	)
)
